FILE_TYPE = MACRO_DRAWING;
SET COLOR_WIRE YELLOW;
SET COLOR_PROP ORANGE;
SET COLOR_DOT WHITE;
SET COLOR_ARC YELLOW;
SET COLOR_BODY GREEN;
SET COLOR_NOTE PURPLE;
SET PROP_DISPLAY VALUE;
SET PAGE_NUMBER P78;
FORCEADD QUANTA_TITLE_BLOCK_C..1
(0 0);
FORCEPROP 1 LAST CUSTOM_TXT_CDS <NAME_2>
J 0
(-3175 50);
FORCEPROP 1 LAST CUSTOM_TXT_CDS <NAME_1>
J 0
(-3175 175);
FORCEPROP 1 LAST CUSTOM_TXT_CDS <Q_NUMBER>
J 0
(-1403 103);
DISPLAY 1.212766 (-1403 103);
FORCEPROP 1 LAST CUSTOM_TXT_CDS <Q_PROJ>
J 0
(-2382 102);
DISPLAY 1.212766 (-2382 102);
FORCEPROP 1 LAST CUSTOM_TXT_CDS <Q_REV>
J 0
(-184 103);
DISPLAY 1.212766 (-184 103);
FORCEPROP 1 LAST CUSTOM_TXT_CDS <CON_LAST_MODIFIED>
J 0
(-1885 15);
DISPLAY 0.978723 (-1885 15);
FORCEPROP 1 LAST CUSTOM_TXT_CDS <CON_PAGE_NUM> OF <CON_TOTAL_PAGES>
J 0
(-446 18);
DISPLAY 0.978723 (-446 18);
FORCEPROP 1 LAST Q_DEPT BU9
J 1
(-3763 49);
DISPLAY 1.957447 (-3763 49);
PAINT GREEN (-3763 49);
FORCEPROP 1 LAST Q_TITLE Blank
J 0
(-9250 75);
DISPLAY 2.446809 (-9250 75);
PAINT GREEN (-9250 75);
FORCEPROP 0 LAST CDS_CON_LAST_MODIFIED Wed Jul 21 11:35:16 2021
J 0
(-1885 15);
DISPLAY INVISIBLE (-1885 15);
FORCEPROP 2 LAST PAGE_BORDER TRUE
J 0
(-7890 5250);
DISPLAY 0.638298 (-7890 5250);
PAINT PINK (-7890 5250);
DISPLAY INVISIBLE (-7890 5250);
FORCEPROP 1 LAST CDS_LMAN_SYM_OUTLINE -9475,6775,100,-125
J 0
(0 0);
DISPLAY 0.468085 (0 0);
PAINT GREEN (0 0);
DISPLAY INVISIBLE (0 0);
FORCEPROP 2 LAST CDS_LIB pure_quanta
J 0
(0 0);
DISPLAY INVISIBLE (0 0);
FORCEPROP 1 LAST COMMENT_BODY TRUE
J 0
(12 -13);
DISPLAY 0.978723 (12 -13);
PAINT GREEN (12 -13);
DISPLAY INVISIBLE (12 -13);
FORCEPROP 2 LAST CUSTOM_TXT_CDS <XR_PAGE_TITLE>
J 0
(-7890 5250);
DISPLAY 0.638298 (-7890 5250);
PAINT PINK (-7890 5250);
DISPLAY INVISIBLE (-7890 5250);
FORCEPROP 2 LAST CDS_XR_PAGE_TITLE CR-78 : @T6G_MB_LIB.T6G(SCH_1):PAGE78
J 0
(-7890 5250);
DISPLAY 0.638298 (-7890 5250);
PAINT PINK (-7890 5250);
DISPLAY INVISIBLE (-7890 5250);
QUIT
